(kicad_pcb
	(version 20260206)
	(generator "pcbnew")
	(generator_version "10.0")
	(general
		(thickness 1.6)
		(legacy_teardrops no)
	)
	(paper "A4")
	(title_block
		(title "04192023_DAF0TMB3IC0_F0TG_MB_C_brd_V02_OCP.brd")
		(comment 1 "Grand Teton / footprint 2783 of 8354 (U26), pads 1990-2104 of 6102")
	)
	(layers
		(0 "F.Cu" signal "TOP")
		(4 "In1.Cu" signal "GND")
		(6 "In2.Cu" signal "IN1")
		(8 "In3.Cu" signal "GND1")
		(10 "In4.Cu" signal "IN2")
		(12 "In5.Cu" signal "GND2")
		(14 "In6.Cu" signal "IN3")
		(16 "In7.Cu" signal "GND3")
		(18 "In8.Cu" signal "VCC")
		(20 "In9.Cu" signal "VCC1")
		(22 "In10.Cu" signal "GND4")
		(24 "In11.Cu" signal "IN4")
		(26 "In12.Cu" signal "GND5")
		(28 "In13.Cu" signal "IN5")
		(30 "In14.Cu" signal "GND6")
		(32 "In15.Cu" signal "IN6")
		(34 "In16.Cu" signal "GND7")
		(2 "B.Cu" signal "BOTTOM")
		(9 "F.Adhes" user "F.Adhesive")
		(11 "B.Adhes" user "B.Adhesive")
		(13 "F.Paste" user "Package Geometry/Pastemask Top")
		(15 "B.Paste" user "Package Geometry/Pastemask Bottom")
		(5 "F.SilkS" user "Ref Des/Silkscreen Top")
		(7 "B.SilkS" user "Ref Des/Silkscreen Bottom")
		(1 "F.Mask" user "Board Geometry/Soldermask Top")
		(3 "B.Mask" user "Board Geometry/Soldermask Bottom")
		(17 "Dwgs.User" user "User.Drawings")
		(19 "Cmts.User" user "User.Comments")
		(21 "Eco1.User" user "User.Eco1")
		(23 "Eco2.User" user "User.Eco2")
		(25 "Edge.Cuts" user "Board Geometry/Outline")
		(27 "Margin" user)
		(31 "F.CrtYd" user "Package Geometry/Place Bound Top")
		(29 "B.CrtYd" user "Package Geometry/Place Bound Bottom")
		(35 "F.Fab" user "Ref Des/Assembly Top")
		(33 "B.Fab" user "Ref Des/Assembly Bottom")
	)
	(footprint ""
		(layer "F.Cu")
		(at 111.927894 -258.880356 180)
		(property "Reference" "U26"
			(at -45.05579 -61.794136 0)
			(unlocked yes)
			(layer "F.SilkS")
			(effects
				(font
					(size 0.7874 0.5842)
					(thickness 0.1524)
				)
			)
		)
		(property "Value" ""
			(at 0 0 180)
			(layer "F.Fab")
			(effects
				(font
					(size 1.27 1.27)
				)
			)
		)
		(duplicate_pad_numbers_are_jumpers no)
		(pad "BK13" smd circle
			(at -23.64994 5.219954 180)
			(size 0.450088 0.450088)
			(layers "F.Cu" "F.Mask" "F.Paste")
			(net "M_H_CPU1_SB_CA<6>")
		)
		(pad "BK14" smd circle
			(at -22.709886 5.219954 180)
			(size 0.450088 0.450088)
			(layers "F.Cu" "F.Mask" "F.Paste")
			(net "M_H_CPU1_SB_CA<5>")
		)
		(pad "BK15" smd circle
			(at -21.770086 5.219954 180)
			(size 0.450088 0.450088)
			(layers "F.Cu" "F.Mask" "F.Paste")
			(net "GND")
		)
		(pad "BK16" smd circle
			(at -20.830032 5.219954 180)
			(size 0.450088 0.450088)
			(layers "F.Cu" "F.Mask" "F.Paste")
			(net "M_J_CPU1_SB_CA<6>")
		)
		(pad "BK17" smd circle
			(at -19.889978 5.219954 180)
			(size 0.450088 0.450088)
			(layers "F.Cu" "F.Mask" "F.Paste")
			(net "GND")
		)
		(pad "BK18" smd circle
			(at -18.949924 5.219954 180)
			(size 0.450088 0.450088)
			(layers "F.Cu" "F.Mask" "F.Paste")
			(net "M_J_CPU1_SB_CA<5>")
		)
		(pad "BK19" smd circle
			(at -18.010124 5.219954 180)
			(size 0.450088 0.450088)
			(layers "F.Cu" "F.Mask" "F.Paste")
			(net "GND")
		)
		(pad "BK20" smd circle
			(at -17.07007 5.219954 180)
			(size 0.450088 0.450088)
			(layers "F.Cu" "F.Mask" "F.Paste")
			(net "M_I_CPU1_SB_CA<6>")
		)
		(pad "BK21" smd circle
			(at -16.130016 5.219954 180)
			(size 0.450088 0.450088)
			(layers "F.Cu" "F.Mask" "F.Paste")
			(net "M_I_CPU1_SB_CA<5>")
		)
		(pad "BK22" smd circle
			(at -15.189962 5.219954 180)
			(size 0.450088 0.450088)
			(layers "F.Cu" "F.Mask" "F.Paste")
			(net "PVDD11_S3_P1")
		)
		(pad "BK23" smd circle
			(at -14.249908 5.219954 180)
			(size 0.450088 0.450088)
			(layers "F.Cu" "F.Mask" "F.Paste")
			(net "GND")
		)
		(pad "BK24" smd circle
			(at -13.310108 5.219954 180)
			(size 0.450088 0.450088)
			(layers "F.Cu" "F.Mask" "F.Paste")
			(net "PVDD11_S3_P1")
		)
		(pad "BK25" smd circle
			(at -12.370054 5.219954 180)
			(size 0.450088 0.450088)
			(layers "F.Cu" "F.Mask" "F.Paste")
			(net "GND")
		)
		(pad "BK26" smd circle
			(at -11.43 5.219954 180)
			(size 0.450088 0.450088)
			(layers "F.Cu" "F.Mask" "F.Paste")
			(net "PVDD11_S3_P1")
		)
		(pad "BK27" smd circle
			(at -10.489946 5.219954 180)
			(size 0.450088 0.450088)
			(layers "F.Cu" "F.Mask" "F.Paste")
			(net "GND")
		)
		(pad "BK28" smd circle
			(at -9.549892 5.219954 180)
			(size 0.450088 0.450088)
			(layers "F.Cu" "F.Mask" "F.Paste")
			(net "PVDD11_S3_P1")
		)
		(pad "BK48" smd circle
			(at 9.249918 5.219954 180)
			(size 0.450088 0.450088)
			(layers "F.Cu" "F.Mask" "F.Paste")
			(net "GND")
		)
		(pad "BK49" smd circle
			(at 10.189972 5.219954 180)
			(size 0.450088 0.450088)
			(layers "F.Cu" "F.Mask" "F.Paste")
			(net "PVDD11_S3_P1")
		)
		(pad "BK50" smd circle
			(at 11.130026 5.219954 180)
			(size 0.450088 0.450088)
			(layers "F.Cu" "F.Mask" "F.Paste")
			(net "GND")
		)
		(pad "BK51" smd circle
			(at 12.07008 5.219954 180)
			(size 0.450088 0.450088)
			(layers "F.Cu" "F.Mask" "F.Paste")
			(net "PVDDIO_P1")
		)
		(pad "BK52" smd circle
			(at 13.00988 5.219954 180)
			(size 0.450088 0.450088)
			(layers "F.Cu" "F.Mask" "F.Paste")
			(net "GND")
		)
		(pad "BK53" smd circle
			(at 13.949934 5.219954 180)
			(size 0.450088 0.450088)
			(layers "F.Cu" "F.Mask" "F.Paste")
			(net "PVDDIO_P1")
		)
		(pad "BK54" smd circle
			(at 14.889988 5.219954 180)
			(size 0.450088 0.450088)
			(layers "F.Cu" "F.Mask" "F.Paste")
			(net "GND")
		)
		(pad "BK55" smd circle
			(at 15.830042 5.219954 180)
			(size 0.450088 0.450088)
			(layers "F.Cu" "F.Mask" "F.Paste")
			(net "M_C_CPU1_SB_CA<5>")
		)
		(pad "BK56" smd circle
			(at 16.770096 5.219954 180)
			(size 0.450088 0.450088)
			(layers "F.Cu" "F.Mask" "F.Paste")
			(net "M_C_CPU1_SB_CA<6>")
		)
		(pad "BK57" smd circle
			(at 17.709896 5.219954 180)
			(size 0.450088 0.450088)
			(layers "F.Cu" "F.Mask" "F.Paste")
			(net "GND")
		)
		(pad "BK58" smd circle
			(at 18.64995 5.219954 180)
			(size 0.450088 0.450088)
			(layers "F.Cu" "F.Mask" "F.Paste")
			(net "M_D_CPU1_SB_CA<5>")
		)
		(pad "BK59" smd circle
			(at 19.590004 5.219954 180)
			(size 0.450088 0.450088)
			(layers "F.Cu" "F.Mask" "F.Paste")
			(net "GND")
		)
		(pad "BK60" smd circle
			(at 20.530058 5.219954 180)
			(size 0.450088 0.450088)
			(layers "F.Cu" "F.Mask" "F.Paste")
			(net "M_D_CPU1_SB_CA<6>")
		)
		(pad "BK61" smd circle
			(at 21.470112 5.219954 180)
			(size 0.450088 0.450088)
			(layers "F.Cu" "F.Mask" "F.Paste")
			(net "GND")
		)
		(pad "BK62" smd circle
			(at 22.409912 5.219954 180)
			(size 0.450088 0.450088)
			(layers "F.Cu" "F.Mask" "F.Paste")
			(net "M_B_CPU1_SB_CA<5>")
		)
		(pad "BK63" smd circle
			(at 23.349966 5.219954 180)
			(size 0.450088 0.450088)
			(layers "F.Cu" "F.Mask" "F.Paste")
			(net "M_B_CPU1_SB_CA<6>")
		)
		(pad "BK64" smd circle
			(at 24.29002 5.219954 180)
			(size 0.450088 0.450088)
			(layers "F.Cu" "F.Mask" "F.Paste")
			(net "GND")
		)
		(pad "BK65" smd circle
			(at 25.230074 5.219954 180)
			(size 0.450088 0.450088)
			(layers "F.Cu" "F.Mask" "F.Paste")
			(net "M_F_CPU1_SB_CA<5>")
		)
		(pad "BK66" smd circle
			(at 26.170128 5.219954 180)
			(size 0.450088 0.450088)
			(layers "F.Cu" "F.Mask" "F.Paste")
			(net "GND")
		)
		(pad "BK67" smd circle
			(at 27.109928 5.219954 180)
			(size 0.450088 0.450088)
			(layers "F.Cu" "F.Mask" "F.Paste")
			(net "M_F_CPU1_SB_CA<6>")
		)
		(pad "BK68" smd circle
			(at 28.049982 5.219954 180)
			(size 0.450088 0.450088)
			(layers "F.Cu" "F.Mask" "F.Paste")
			(net "GND")
		)
		(pad "BK69" smd circle
			(at 28.990036 5.219954 180)
			(size 0.450088 0.450088)
			(layers "F.Cu" "F.Mask" "F.Paste")
			(net "M_E_CPU1_SB_CA<5>")
		)
		(pad "BK70" smd circle
			(at 29.93009 5.219954 180)
			(size 0.450088 0.450088)
			(layers "F.Cu" "F.Mask" "F.Paste")
			(net "M_E_CPU1_SB_CA<6>")
		)
		(pad "BK71" smd circle
			(at 30.86989 5.219954 180)
			(size 0.450088 0.450088)
			(layers "F.Cu" "F.Mask" "F.Paste")
			(net "GND")
		)
		(pad "BK72" smd circle
			(at 31.809944 5.219954 180)
			(size 0.450088 0.450088)
			(layers "F.Cu" "F.Mask" "F.Paste")
			(net "M_A_CPU1_SB_CA<5>")
		)
		(pad "BK73" smd circle
			(at 32.749998 5.219954 180)
			(size 0.450088 0.450088)
			(layers "F.Cu" "F.Mask" "F.Paste")
			(net "GND")
		)
		(pad "BK74" smd circle
			(at 33.690052 5.219954 180)
			(size 0.450088 0.450088)
			(layers "F.Cu" "F.Mask" "F.Paste")
			(net "M_A_CPU1_SB_CA<6>")
		)
		(pad "BL1" smd circle
			(at -34.459926 6.02996 180)
			(size 0.450088 0.450088)
			(layers "F.Cu" "F.Mask" "F.Paste")
			(net "GND")
		)
		(pad "BL2" smd circle
			(at -33.519872 6.02996 180)
			(size 0.450088 0.450088)
			(layers "F.Cu" "F.Mask" "F.Paste")
			(net "Net_2043")
		)
		(pad "BL3" smd circle
			(at -32.580072 6.02996 180)
			(size 0.450088 0.450088)
			(layers "F.Cu" "F.Mask" "F.Paste")
			(net "M_G_CPU1_SB_PAR")
		)
		(pad "BL4" smd circle
			(at -31.640018 6.02996 180)
			(size 0.450088 0.450088)
			(layers "F.Cu" "F.Mask" "F.Paste")
			(net "GND")
		)
		(pad "BL5" smd circle
			(at -30.699964 6.02996 180)
			(size 0.450088 0.450088)
			(layers "F.Cu" "F.Mask" "F.Paste")
			(net "Net_2192")
		)
		(pad "BL6" smd circle
			(at -29.75991 6.02996 180)
			(size 0.450088 0.450088)
			(layers "F.Cu" "F.Mask" "F.Paste")
			(net "GND")
		)
		(pad "BL7" smd circle
			(at -28.82011 6.02996 180)
			(size 0.450088 0.450088)
			(layers "F.Cu" "F.Mask" "F.Paste")
			(net "M_K_CPU1_SB_PAR")
		)
		(pad "BL8" smd circle
			(at -27.880056 6.02996 180)
			(size 0.450088 0.450088)
			(layers "F.Cu" "F.Mask" "F.Paste")
			(net "GND")
		)
		(pad "BL9" smd circle
			(at -26.940002 6.02996 180)
			(size 0.450088 0.450088)
			(layers "F.Cu" "F.Mask" "F.Paste")
			(net "Net_2184")
		)
		(pad "BL10" smd circle
			(at -25.999948 6.02996 180)
			(size 0.450088 0.450088)
			(layers "F.Cu" "F.Mask" "F.Paste")
			(net "M_L_CPU1_SB_PAR")
		)
		(pad "BL11" smd circle
			(at -25.059894 6.02996 180)
			(size 0.450088 0.450088)
			(layers "F.Cu" "F.Mask" "F.Paste")
			(net "GND")
		)
		(pad "BL12" smd circle
			(at -24.120094 6.02996 180)
			(size 0.450088 0.450088)
			(layers "F.Cu" "F.Mask" "F.Paste")
			(net "Net_2051")
		)
		(pad "BL13" smd circle
			(at -23.18004 6.02996 180)
			(size 0.450088 0.450088)
			(layers "F.Cu" "F.Mask" "F.Paste")
			(net "GND")
		)
		(pad "BL14" smd circle
			(at -22.239986 6.02996 180)
			(size 0.450088 0.450088)
			(layers "F.Cu" "F.Mask" "F.Paste")
			(net "M_H_CPU1_SB_PAR")
		)
		(pad "BL15" smd circle
			(at -21.299932 6.02996 180)
			(size 0.450088 0.450088)
			(layers "F.Cu" "F.Mask" "F.Paste")
			(net "GND")
		)
		(pad "BL16" smd circle
			(at -20.359878 6.02996 180)
			(size 0.450088 0.450088)
			(layers "F.Cu" "F.Mask" "F.Paste")
			(net "Net_2067")
		)
		(pad "BL17" smd circle
			(at -19.420078 6.02996 180)
			(size 0.450088 0.450088)
			(layers "F.Cu" "F.Mask" "F.Paste")
			(net "M_J_CPU1_SB_PAR")
		)
		(pad "BL18" smd circle
			(at -18.480024 6.02996 180)
			(size 0.450088 0.450088)
			(layers "F.Cu" "F.Mask" "F.Paste")
			(net "GND")
		)
		(pad "BL19" smd circle
			(at -17.53997 6.02996 180)
			(size 0.450088 0.450088)
			(layers "F.Cu" "F.Mask" "F.Paste")
			(net "Net_2059")
		)
		(pad "BL20" smd circle
			(at -16.599916 6.02996 180)
			(size 0.450088 0.450088)
			(layers "F.Cu" "F.Mask" "F.Paste")
			(net "GND")
		)
		(pad "BL21" smd circle
			(at -15.660116 6.02996 180)
			(size 0.450088 0.450088)
			(layers "F.Cu" "F.Mask" "F.Paste")
			(net "M_I_CPU1_SB_PAR")
		)
		(pad "BL22" smd circle
			(at -14.720062 6.02996 180)
			(size 0.450088 0.450088)
			(layers "F.Cu" "F.Mask" "F.Paste")
			(net "GND")
		)
		(pad "BL23" smd circle
			(at -13.780008 6.02996 180)
			(size 0.450088 0.450088)
			(layers "F.Cu" "F.Mask" "F.Paste")
			(net "PVDD11_S3_P1")
		)
		(pad "BL24" smd circle
			(at -12.839954 6.02996 180)
			(size 0.450088 0.450088)
			(layers "F.Cu" "F.Mask" "F.Paste")
			(net "GND")
		)
		(pad "BL25" smd circle
			(at -11.8999 6.02996 180)
			(size 0.450088 0.450088)
			(layers "F.Cu" "F.Mask" "F.Paste")
			(net "PVDD11_S3_P1")
		)
		(pad "BL26" smd circle
			(at -10.9601 6.02996 180)
			(size 0.450088 0.450088)
			(layers "F.Cu" "F.Mask" "F.Paste")
			(net "GND")
		)
		(pad "BL27" smd circle
			(at -10.020046 6.02996 180)
			(size 0.450088 0.450088)
			(layers "F.Cu" "F.Mask" "F.Paste")
			(net "PVDD11_S3_P1")
		)
		(pad "BL28" smd circle
			(at -9.079992 6.02996 180)
			(size 0.450088 0.450088)
			(layers "F.Cu" "F.Mask" "F.Paste")
			(net "GND")
		)
		(pad "BL48" smd circle
			(at 8.780018 6.02996 180)
			(size 0.450088 0.450088)
			(layers "F.Cu" "F.Mask" "F.Paste")
			(net "PVDD11_S3_P1")
		)
		(pad "BL49" smd circle
			(at 9.720072 6.02996 180)
			(size 0.450088 0.450088)
			(layers "F.Cu" "F.Mask" "F.Paste")
			(net "GND")
		)
		(pad "BL50" smd circle
			(at 10.659872 6.02996 180)
			(size 0.450088 0.450088)
			(layers "F.Cu" "F.Mask" "F.Paste")
			(net "PVDDIO_P1")
		)
		(pad "BL51" smd circle
			(at 11.599926 6.02996 180)
			(size 0.450088 0.450088)
			(layers "F.Cu" "F.Mask" "F.Paste")
			(net "GND")
		)
		(pad "BL52" smd circle
			(at 12.53998 6.02996 180)
			(size 0.450088 0.450088)
			(layers "F.Cu" "F.Mask" "F.Paste")
			(net "PVDDIO_P1")
		)
		(pad "BL53" smd circle
			(at 13.480034 6.02996 180)
			(size 0.450088 0.450088)
			(layers "F.Cu" "F.Mask" "F.Paste")
			(net "GND")
		)
		(pad "BL54" smd circle
			(at 14.420088 6.02996 180)
			(size 0.450088 0.450088)
			(layers "F.Cu" "F.Mask" "F.Paste")
			(net "PVDDIO_P1")
		)
		(pad "BL55" smd circle
			(at 15.359888 6.02996 180)
			(size 0.450088 0.450088)
			(layers "F.Cu" "F.Mask" "F.Paste")
			(net "Net_2011")
		)
		(pad "BL56" smd circle
			(at 16.299942 6.02996 180)
			(size 0.450088 0.450088)
			(layers "F.Cu" "F.Mask" "F.Paste")
			(net "GND")
		)
		(pad "BL57" smd circle
			(at 17.239996 6.02996 180)
			(size 0.450088 0.450088)
			(layers "F.Cu" "F.Mask" "F.Paste")
			(net "M_C_CPU1_SB_PAR")
		)
		(pad "BL58" smd circle
			(at 18.18005 6.02996 180)
			(size 0.450088 0.450088)
			(layers "F.Cu" "F.Mask" "F.Paste")
			(net "GND")
		)
		(pad "BL59" smd circle
			(at 19.120104 6.02996 180)
			(size 0.450088 0.450088)
			(layers "F.Cu" "F.Mask" "F.Paste")
			(net "Net_2019")
		)
		(pad "BL60" smd circle
			(at 20.059904 6.02996 180)
			(size 0.450088 0.450088)
			(layers "F.Cu" "F.Mask" "F.Paste")
			(net "M_D_CPU1_SB_PAR")
		)
		(pad "BL61" smd circle
			(at 20.999958 6.02996 180)
			(size 0.450088 0.450088)
			(layers "F.Cu" "F.Mask" "F.Paste")
			(net "GND")
		)
		(pad "BL62" smd circle
			(at 21.940012 6.02996 180)
			(size 0.450088 0.450088)
			(layers "F.Cu" "F.Mask" "F.Paste")
			(net "Net_2003")
		)
		(pad "BL63" smd circle
			(at 22.880066 6.02996 180)
			(size 0.450088 0.450088)
			(layers "F.Cu" "F.Mask" "F.Paste")
			(net "GND")
		)
		(pad "BL64" smd circle
			(at 23.82012 6.02996 180)
			(size 0.450088 0.450088)
			(layers "F.Cu" "F.Mask" "F.Paste")
			(net "M_B_CPU1_SB_PAR")
		)
		(pad "BL65" smd circle
			(at 24.75992 6.02996 180)
			(size 0.450088 0.450088)
			(layers "F.Cu" "F.Mask" "F.Paste")
			(net "GND")
		)
		(pad "BL66" smd circle
			(at 25.699974 6.02996 180)
			(size 0.450088 0.450088)
			(layers "F.Cu" "F.Mask" "F.Paste")
			(net "Net_2035")
		)
		(pad "BL67" smd circle
			(at 26.640028 6.02996 180)
			(size 0.450088 0.450088)
			(layers "F.Cu" "F.Mask" "F.Paste")
			(net "M_F_CPU1_SB_PAR")
		)
		(pad "BL68" smd circle
			(at 27.580082 6.02996 180)
			(size 0.450088 0.450088)
			(layers "F.Cu" "F.Mask" "F.Paste")
			(net "GND")
		)
		(pad "BL69" smd circle
			(at 28.519882 6.02996 180)
			(size 0.450088 0.450088)
			(layers "F.Cu" "F.Mask" "F.Paste")
			(net "Net_2027")
		)
		(pad "BL70" smd circle
			(at 29.459936 6.02996 180)
			(size 0.450088 0.450088)
			(layers "F.Cu" "F.Mask" "F.Paste")
			(net "GND")
		)
		(pad "BL71" smd circle
			(at 30.39999 6.02996 180)
			(size 0.450088 0.450088)
			(layers "F.Cu" "F.Mask" "F.Paste")
			(net "M_E_CPU1_SB_PAR")
		)
		(pad "BL72" smd circle
			(at 31.340044 6.02996 180)
			(size 0.450088 0.450088)
			(layers "F.Cu" "F.Mask" "F.Paste")
			(net "GND")
		)
		(pad "BL73" smd circle
			(at 32.280098 6.02996 180)
			(size 0.450088 0.450088)
			(layers "F.Cu" "F.Mask" "F.Paste")
			(net "Net_1995")
		)
		(pad "BL74" smd circle
			(at 33.219898 6.02996 180)
			(size 0.450088 0.450088)
			(layers "F.Cu" "F.Mask" "F.Paste")
			(net "M_A_CPU1_SB_PAR")
		)
		(pad "BL75" smd circle
			(at 34.159952 6.02996 180)
			(size 0.450088 0.450088)
			(layers "F.Cu" "F.Mask" "F.Paste")
			(net "GND")
		)
		(pad "BM2" smd circle
			(at -33.990026 6.839966 180)
			(size 0.450088 0.450088)
			(layers "F.Cu" "F.Mask" "F.Paste")
			(net "Net_2044")
		)
		(pad "BM3" smd circle
			(at -33.049972 6.839966 180)
			(size 0.450088 0.450088)
			(layers "F.Cu" "F.Mask" "F.Paste")
			(net "GND")
		)
		(pad "BM4" smd circle
			(at -32.109918 6.839966 180)
			(size 0.450088 0.450088)
			(layers "F.Cu" "F.Mask" "F.Paste")
			(net "M_G_CPU1_SB_CS_N<0>")
		)
		(pad "BM5" smd circle
			(at -31.170118 6.839966 180)
			(size 0.450088 0.450088)
			(layers "F.Cu" "F.Mask" "F.Paste")
			(net "PVDDCR_SOC_P1")
		)
		(pad "BM6" smd circle
			(at -30.230064 6.839966 180)
			(size 0.450088 0.450088)
			(layers "F.Cu" "F.Mask" "F.Paste")
			(net "Net_2193")
		)
		(pad "BM7" smd circle
			(at -29.29001 6.839966 180)
			(size 0.450088 0.450088)
			(layers "F.Cu" "F.Mask" "F.Paste")
			(net "M_K_CPU1_SB_CS_N<0>")
		)
		(pad "BM8" smd circle
			(at -28.349956 6.839966 180)
			(size 0.450088 0.450088)
			(layers "F.Cu" "F.Mask" "F.Paste")
			(net "GND")
		)
		(pad "BM9" smd circle
			(at -27.409902 6.839966 180)
			(size 0.450088 0.450088)
			(layers "F.Cu" "F.Mask" "F.Paste")
			(net "Net_2185")
		)
		(pad "BM10" smd circle
			(at -26.470102 6.839966 180)
			(size 0.450088 0.450088)
			(layers "F.Cu" "F.Mask" "F.Paste")
			(net "GND")
		)
		(pad "BM11" smd circle
			(at -25.530048 6.839966 180)
			(size 0.450088 0.450088)
			(layers "F.Cu" "F.Mask" "F.Paste")
			(net "M_L_CPU1_SB_CS_N<0>")
		)
		(pad "BM12" smd circle
			(at -24.589994 6.839966 180)
			(size 0.450088 0.450088)
			(layers "F.Cu" "F.Mask" "F.Paste")
			(net "PVDD11_S3_P1")
		)
		(pad "BM13" smd circle
			(at -23.64994 6.839966 180)
			(size 0.450088 0.450088)
			(layers "F.Cu" "F.Mask" "F.Paste")
			(net "Net_2052")
		)
		(pad "BM14" smd circle
			(at -22.709886 6.839966 180)
			(size 0.450088 0.450088)
			(layers "F.Cu" "F.Mask" "F.Paste")
			(net "M_H_CPU1_SB_CS_N<0>")
		)
		(pad "BM15" smd circle
			(at -21.770086 6.839966 180)
			(size 0.450088 0.450088)
			(layers "F.Cu" "F.Mask" "F.Paste")
			(net "GND")
		)
		(pad "BM16" smd circle
			(at -20.830032 6.839966 180)
			(size 0.450088 0.450088)
			(layers "F.Cu" "F.Mask" "F.Paste")
			(net "Net_2068")
		)
		(pad "BM17" smd circle
			(at -19.889978 6.839966 180)
			(size 0.450088 0.450088)
			(layers "F.Cu" "F.Mask" "F.Paste")
			(net "GND")
		)
	)
)
